(kicad_pcb
	(version 20260206)
	(generator "pcbnew")
	(generator_version "10.0")
	(general
		(thickness 1.6)
		(legacy_teardrops no)
	)
	(paper "A4")
	(title_block
		(title "v1-chassis-manager — T6M_CM_d_v01_1031_1645.brd")
		(comment 1 "Open CloudServer (Microsoft) / footprints 175-180 of 2512")
	)
	(layers
		(0 "F.Cu" signal "TOP")
		(4 "In1.Cu" signal "GND1")
		(6 "In2.Cu" signal "IN1")
		(8 "In3.Cu" signal "VCC1")
		(10 "In4.Cu" signal "VCC2")
		(12 "In5.Cu" signal "GND2")
		(14 "In6.Cu" signal "IN2")
		(16 "In7.Cu" signal "IN3")
		(18 "In8.Cu" signal "GND3")
		(2 "B.Cu" signal "BOTTOM")
		(9 "F.Adhes" user "F.Adhesive")
		(11 "B.Adhes" user "B.Adhesive")
		(13 "F.Paste" user "Package Geometry/Pastemask Top")
		(15 "B.Paste" user "Package Geometry/Pastemask Bottom")
		(5 "F.SilkS" user "Ref Des/Silkscreen Top")
		(7 "B.SilkS" user "Ref Des/Silkscreen Bottom")
		(1 "F.Mask" user "Board Geometry/Soldermask Top")
		(3 "B.Mask" user "Board Geometry/Soldermask Bottom")
		(17 "Dwgs.User" user "User.Drawings")
		(19 "Cmts.User" user "User.Comments")
		(21 "Eco1.User" user "User.Eco1")
		(23 "Eco2.User" user "User.Eco2")
		(25 "Edge.Cuts" user "Board Geometry/Outline")
		(27 "Margin" user)
		(31 "F.CrtYd" user "Package Geometry/Place Bound Top")
		(29 "B.CrtYd" user "Package Geometry/Place Bound Bottom")
		(35 "F.Fab" user "Ref Des/Assembly Top")
		(33 "B.Fab" user "Ref Des/Assembly Bottom")
	)
	(footprint ""
		(layer "F.Cu")
		(at 135.83412 -8.585962 180)
		(property "Reference" "J20"
			(at 6.26872 -3.786632 0)
			(unlocked yes)
			(layer "F.SilkS")
			(effects
				(font
					(size 0.7874 0.5842)
					(thickness 0.1524)
				)
				(justify left)
			)
		)
		(property "Value" ""
			(at 0 0 180)
			(layer "F.Fab")
			(effects
				(font
					(size 1.27 1.27)
				)
			)
		)
		(duplicate_pad_numbers_are_jumpers no)
		(fp_line
			(start 6.599936 2.640076)
			(end -6.599936 2.640076)
			(stroke
				(width 0.1524)
				(type default)
			)
			(layer "F.SilkS")
		)
		(fp_line
			(start 6.599936 -2.640076)
			(end 6.599936 2.640076)
			(stroke
				(width 0.1524)
				(type default)
			)
			(layer "F.SilkS")
		)
		(fp_line
			(start -6.599936 2.640076)
			(end -6.599936 -2.640076)
			(stroke
				(width 0.1524)
				(type default)
			)
			(layer "F.SilkS")
		)
		(fp_line
			(start -6.599936 -2.640076)
			(end 6.599936 -2.640076)
			(stroke
				(width 0.1524)
				(type default)
			)
			(layer "F.SilkS")
		)
		(fp_poly
			(pts
				(xy -4.905502 3.179572) (xy -5.667502 5.084572) (xy -4.143502 5.084572)
			)
			(stroke
				(width 0)
				(type default)
			)
			(fill yes)
			(layer "F.SilkS")
		)
		(fp_poly
			(pts
				(xy -5.969 -2.159) (xy 5.969 -2.159) (xy 5.969 2.159) (xy -5.969 2.159)
			)
			(stroke
				(width 0)
				(type default)
			)
			(fill no)
			(layer "B.CrtYd")
		)
		(fp_poly
			(pts
				(xy -6.599936 2.640076) (xy 6.599936 2.640076) (xy 6.599936 -2.640076) (xy -6.599936 -2.640076)
			)
			(stroke
				(width 0)
				(type default)
			)
			(fill no)
			(layer "F.CrtYd")
		)
		(fp_line
			(start 6.599936 2.640076)
			(end -6.599936 2.640076)
			(stroke
				(width 0.1)
				(type default)
			)
			(layer "F.Fab")
		)
		(fp_line
			(start 6.599936 -2.640076)
			(end 6.599936 2.640076)
			(stroke
				(width 0.1)
				(type default)
			)
			(layer "F.Fab")
		)
		(fp_line
			(start -6.599936 2.640076)
			(end -6.599936 -2.640076)
			(stroke
				(width 0.1)
				(type default)
			)
			(layer "F.Fab")
		)
		(fp_line
			(start -6.599936 -2.640076)
			(end 6.599936 -2.640076)
			(stroke
				(width 0.1)
				(type default)
			)
			(layer "F.Fab")
		)
		(fp_poly
			(pts
				(xy -7.4295 1.27) (xy -9.3345 0.508) (xy -9.3345 2.032)
			)
			(stroke
				(width 0)
				(type default)
			)
			(fill yes)
			(layer "F.Fab")
		)
		(fp_text user "10"
			(at 8.181086 -1.537462 0)
			(unlocked yes)
			(layer "F.SilkS")
			(effects
				(font
					(size 0.7874 0.5842)
					(thickness 0.1524)
				)
				(justify left)
			)
		)
		(fp_text user "9"
			(at 7.361936 1.197864 0)
			(unlocked yes)
			(layer "F.SilkS")
			(effects
				(font
					(size 0.7874 0.5842)
					(thickness 0.1524)
				)
				(justify left)
			)
		)
		(fp_text user "1"
			(at -6.69798 0.931672 0)
			(unlocked yes)
			(layer "F.SilkS")
			(effects
				(font
					(size 0.7874 0.5842)
					(thickness 0.1524)
				)
				(justify left)
			)
		)
		(fp_text user "2"
			(at -6.863842 -1.454404 0)
			(unlocked yes)
			(layer "F.SilkS")
			(effects
				(font
					(size 0.7874 0.5842)
					(thickness 0.1524)
				)
				(justify left)
			)
		)
		(fp_text user "9"
			(at 6.342634 1.367536 0)
			(unlocked yes)
			(layer "B.SilkS")
			(effects
				(font
					(size 0.7874 0.5842)
					(thickness 0.1524)
				)
				(justify left mirror)
			)
		)
		(fp_text user "10"
			(at 6.272784 -1.272286 0)
			(unlocked yes)
			(layer "B.SilkS")
			(effects
				(font
					(size 0.7874 0.5842)
					(thickness 0.1524)
				)
				(justify left mirror)
			)
		)
		(fp_text user "1"
			(at -6.849618 1.245616 0)
			(unlocked yes)
			(layer "B.SilkS")
			(effects
				(font
					(size 0.7874 0.5842)
					(thickness 0.1524)
				)
				(justify left mirror)
			)
		)
		(fp_text user "2"
			(at -6.90245 -1.342136 0)
			(unlocked yes)
			(layer "B.SilkS")
			(effects
				(font
					(size 0.7874 0.5842)
					(thickness 0.1524)
				)
				(justify left mirror)
			)
		)
		(fp_text user "10"
			(at 7.5438 -1.361948 180)
			(unlocked yes)
			(layer "B.Fab")
			(effects
				(font
					(size 0.7874 0.5842)
					(thickness 0.000001)
				)
				(justify left mirror)
			)
		)
		(fp_text user "9"
			(at 7.1501 1.178052 180)
			(unlocked yes)
			(layer "B.Fab")
			(effects
				(font
					(size 0.7874 0.5842)
					(thickness 0.000001)
				)
				(justify left mirror)
			)
		)
		(fp_text user "1"
			(at -6.1849 1.178052 180)
			(unlocked yes)
			(layer "B.Fab")
			(effects
				(font
					(size 0.7874 0.5842)
					(thickness 0.000001)
				)
				(justify left mirror)
			)
		)
		(fp_text user "2"
			(at -6.1849 -1.361948 180)
			(unlocked yes)
			(layer "B.Fab")
			(effects
				(font
					(size 0.7874 0.5842)
					(thickness 0.000001)
				)
				(justify left mirror)
			)
		)
		(fp_text user "9"
			(at 6.9469 1.178052 180)
			(unlocked yes)
			(layer "F.Fab")
			(effects
				(font
					(size 0.7874 0.5842)
					(thickness 0.000001)
				)
				(justify left)
			)
		)
		(fp_text user "10"
			(at 6.5532 -1.361948 180)
			(unlocked yes)
			(layer "F.Fab")
			(effects
				(font
					(size 0.7874 0.5842)
					(thickness 0.000001)
				)
				(justify left)
			)
		)
		(fp_text user "1"
			(at -7.5311 1.178052 180)
			(unlocked yes)
			(layer "F.Fab")
			(effects
				(font
					(size 0.7874 0.5842)
					(thickness 0.000001)
				)
				(justify left)
			)
		)
		(fp_text user "2"
			(at -7.5311 -1.361948 180)
			(unlocked yes)
			(layer "F.Fab")
			(effects
				(font
					(size 0.7874 0.5842)
					(thickness 0.000001)
				)
				(justify left)
			)
		)
		(pad "1" thru_hole rect
			(at -5.08 1.27 270)
			(size 1.6764 1.6764)
			(drill 1.1684)
			(layers "*.Cu" "*.Mask")
			(remove_unused_layers no)
			(net "JTAG_CPLD1_TCK")
			(clearance 0)
			(padstack
				(mode front_inner_back)
				(layer "Inner"
					(shape circle)
					(size 1.6764 1.6764)
					(clearance 0)
				)
				(layer "B.Cu"
					(shape rect)
					(size 1.6764 1.6764)
					(clearance 0)
				)
			)
		)
		(pad "2" thru_hole circle
			(at -5.08 -1.27 270)
			(size 1.6764 1.6764)
			(drill 1.1684)
			(layers "*.Cu" "*.Mask")
			(remove_unused_layers no)
			(net "GND")
			(clearance 0)
		)
		(pad "3" thru_hole circle
			(at -2.54 1.27 270)
			(size 1.6764 1.6764)
			(drill 1.1684)
			(layers "*.Cu" "*.Mask")
			(remove_unused_layers no)
			(net "JTAG_CPLD1_TDO")
			(clearance 0)
		)
		(pad "4" thru_hole circle
			(at -2.54 -1.27 270)
			(size 1.6764 1.6764)
			(drill 1.1684)
			(layers "*.Cu" "*.Mask")
			(remove_unused_layers no)
			(net "P3V3_STB_NODE1")
			(clearance 0)
		)
		(pad "5" thru_hole circle
			(at 0 1.27 270)
			(size 1.6764 1.6764)
			(drill 1.1684)
			(layers "*.Cu" "*.Mask")
			(remove_unused_layers no)
			(net "JTAG_CPLD1_TMS")
			(clearance 0)
		)
		(pad "6" thru_hole circle
			(at 0 -1.27 270)
			(size 1.6764 1.6764)
			(drill 1.1684)
			(layers "*.Cu" "*.Mask")
			(remove_unused_layers no)
			(net "Net_583")
			(clearance 0)
		)
		(pad "7" thru_hole circle
			(at 2.54 1.27 270)
			(size 1.6764 1.6764)
			(drill 1.1684)
			(layers "*.Cu" "*.Mask")
			(remove_unused_layers no)
			(net "Net_581")
			(clearance 0)
		)
		(pad "8" thru_hole circle
			(at 2.54 -1.27 270)
			(size 1.6764 1.6764)
			(drill 1.1684)
			(layers "*.Cu" "*.Mask")
			(remove_unused_layers no)
			(net "Net_582")
			(clearance 0)
		)
		(pad "9" thru_hole circle
			(at 5.08 1.27 270)
			(size 1.6764 1.6764)
			(drill 1.1684)
			(layers "*.Cu" "*.Mask")
			(remove_unused_layers no)
			(net "JTAG_CPLD1_TDI")
			(clearance 0)
		)
		(pad "10" thru_hole circle
			(at 5.08 -1.27 270)
			(size 1.6764 1.6764)
			(drill 1.1684)
			(layers "*.Cu" "*.Mask")
			(remove_unused_layers no)
			(net "GND")
			(clearance 0)
		)
	)
	(footprint ""
		(layer "F.Cu")
		(at 130.48107 -154.696668 180)
		(property "Reference" "R297"
			(at 61.214 -110.034832 0)
			(unlocked yes)
			(layer "F.SilkS")
			(effects
				(font
					(size 0.7874 0.5842)
					(thickness 0.1524)
				)
				(justify left)
			)
		)
		(property "Value" ""
			(at 0 0 180)
			(layer "F.Fab")
			(effects
				(font
					(size 1.27 1.27)
				)
			)
		)
		(duplicate_pad_numbers_are_jumpers no)
		(fp_line
			(start 0.7874 0.4064)
			(end -0.7874 0.4064)
			(stroke
				(width 0.1524)
				(type default)
			)
			(layer "F.SilkS")
		)
		(fp_line
			(start 0.7874 -0.4064)
			(end 0.7874 0.4064)
			(stroke
				(width 0.1524)
				(type default)
			)
			(layer "F.SilkS")
		)
		(fp_line
			(start -0.7874 0.4064)
			(end -0.7874 -0.4064)
			(stroke
				(width 0.1524)
				(type default)
			)
			(layer "F.SilkS")
		)
		(fp_line
			(start -0.7874 -0.4064)
			(end 0.7874 -0.4064)
			(stroke
				(width 0.1524)
				(type default)
			)
			(layer "F.SilkS")
		)
		(fp_poly
			(pts
				(xy -0.508 0.2794) (xy -0.508 0.2286) (xy -0.635 0.2286) (xy -0.635 -0.254) (xy -0.5334 -0.254)
				(xy -0.5334 -0.2794) (xy 0.5334 -0.2794) (xy 0.5334 -0.254) (xy 0.635 -0.254) (xy 0.635 0.254) (xy 0.5334 0.254)
				(xy 0.5334 0.2794)
			)
			(stroke
				(width 0)
				(type default)
			)
			(fill no)
			(layer "F.CrtYd")
		)
		(pad "1" smd rect
			(at 0.40005 0 180)
			(size 0.4572 0.508)
			(layers "F.Cu" "F.Mask" "F.Paste")
			(net "P3V3_NODE1")
		)
		(pad "2" smd rect
			(at -0.40005 0 180)
			(size 0.4572 0.508)
			(layers "F.Cu" "F.Mask" "F.Paste")
			(net "PCIE_SW_SCAN_EN")
		)
	)
	(footprint ""
		(layer "F.Cu")
		(at 44.567602 -163.558982 180)
		(property "Reference" "C400"
			(at 0.520192 -1.569466 0)
			(unlocked yes)
			(layer "F.SilkS")
			(effects
				(font
					(size 0.7874 0.5842)
					(thickness 0.1524)
				)
				(justify left)
			)
		)
		(property "Value" ""
			(at 0 0 180)
			(layer "F.Fab")
			(effects
				(font
					(size 1.27 1.27)
				)
			)
		)
		(duplicate_pad_numbers_are_jumpers no)
		(fp_line
			(start 0.7874 0.4064)
			(end -0.7874 0.4064)
			(stroke
				(width 0.1524)
				(type default)
			)
			(layer "F.SilkS")
		)
		(fp_line
			(start 0.7874 -0.4064)
			(end 0.7874 0.4064)
			(stroke
				(width 0.1524)
				(type default)
			)
			(layer "F.SilkS")
		)
		(fp_line
			(start 0 0.381)
			(end 0 -0.381)
			(stroke
				(width 0.1524)
				(type default)
			)
			(layer "F.SilkS")
		)
		(fp_line
			(start -0.7874 0.4064)
			(end -0.7874 -0.4064)
			(stroke
				(width 0.1524)
				(type default)
			)
			(layer "F.SilkS")
		)
		(fp_line
			(start -0.7874 -0.4064)
			(end 0.7874 -0.4064)
			(stroke
				(width 0.1524)
				(type default)
			)
			(layer "F.SilkS")
		)
		(fp_poly
			(pts
				(xy -0.5334 0.254) (xy -0.635 0.254) (xy -0.635 0.2286) (xy -0.635 -0.254) (xy -0.5334 -0.254) (xy -0.5334 -0.2794)
				(xy 0.5334 -0.2794) (xy 0.5334 -0.254) (xy 0.635 -0.254) (xy 0.635 0.254) (xy 0.5334 0.254) (xy 0.5334 0.2794)
				(xy -0.508 0.2794) (xy -0.5334 0.2794)
			)
			(stroke
				(width 0)
				(type default)
			)
			(fill no)
			(layer "F.CrtYd")
		)
		(pad "1" smd rect
			(at 0.40005 0 180)
			(size 0.4572 0.508)
			(layers "F.Cu" "F.Mask" "F.Paste")
			(net "LAN1_XTAL_OUT")
		)
		(pad "2" smd rect
			(at -0.40005 0 180)
			(size 0.4572 0.508)
			(layers "F.Cu" "F.Mask" "F.Paste")
			(net "GND")
		)
	)
	(footprint ""
		(layer "F.Cu")
		(at 69.547486 -148.476462 90)
		(property "Reference" "R300"
			(at 1.233932 -0.049784 90)
			(unlocked yes)
			(layer "F.SilkS")
			(effects
				(font
					(size 0.7874 0.5842)
					(thickness 0.1524)
				)
				(justify left)
			)
		)
		(property "Value" ""
			(at 0 0 90)
			(layer "F.Fab")
			(effects
				(font
					(size 1.27 1.27)
				)
			)
		)
		(duplicate_pad_numbers_are_jumpers no)
		(fp_line
			(start 0.7874 -0.4064)
			(end 0.7874 0.4064)
			(stroke
				(width 0.1524)
				(type default)
			)
			(layer "F.SilkS")
		)
		(fp_line
			(start -0.7874 -0.4064)
			(end 0.7874 -0.4064)
			(stroke
				(width 0.1524)
				(type default)
			)
			(layer "F.SilkS")
		)
		(fp_line
			(start 0.7874 0.4064)
			(end -0.7874 0.4064)
			(stroke
				(width 0.1524)
				(type default)
			)
			(layer "F.SilkS")
		)
		(fp_line
			(start -0.7874 0.4064)
			(end -0.7874 -0.4064)
			(stroke
				(width 0.1524)
				(type default)
			)
			(layer "F.SilkS")
		)
		(fp_poly
			(pts
				(xy -0.508 0.2794) (xy -0.508 0.2286) (xy -0.635 0.2286) (xy -0.635 -0.254) (xy -0.5334 -0.254)
				(xy -0.5334 -0.2794) (xy 0.5334 -0.2794) (xy 0.5334 -0.254) (xy 0.635 -0.254) (xy 0.635 0.254) (xy 0.5334 0.254)
				(xy 0.5334 0.2794)
			)
			(stroke
				(width 0)
				(type default)
			)
			(fill no)
			(layer "F.CrtYd")
		)
		(pad "1" smd rect
			(at 0.40005 0 90)
			(size 0.4572 0.508)
			(layers "F.Cu" "F.Mask" "F.Paste")
			(net "P3V3_NODE1")
		)
		(pad "2" smd rect
			(at -0.40005 0 90)
			(size 0.4572 0.508)
			(layers "F.Cu" "F.Mask" "F.Paste")
			(net "BMC_NODE1_JTAG_TDI")
		)
	)
	(footprint ""
		(layer "F.Cu")
		(at 17.982184 -66.847466 180)
		(property "Reference" "U49"
			(at -2.942336 -0.121666 0)
			(unlocked yes)
			(layer "F.SilkS")
			(effects
				(font
					(size 0.7874 0.5842)
					(thickness 0.1524)
				)
			)
		)
		(property "Value" ""
			(at 0 0 180)
			(layer "F.Fab")
			(effects
				(font
					(size 1.27 1.27)
				)
			)
		)
		(duplicate_pad_numbers_are_jumpers no)
		(fp_line
			(start 1.651 1.905)
			(end -1.651 1.905)
			(stroke
				(width 0.1524)
				(type default)
			)
			(layer "F.SilkS")
		)
		(fp_line
			(start 1.651 -1.905)
			(end 1.651 1.905)
			(stroke
				(width 0.1524)
				(type default)
			)
			(layer "F.SilkS")
		)
		(fp_line
			(start -1.651 1.905)
			(end -1.651 -1.905)
			(stroke
				(width 0.1524)
				(type default)
			)
			(layer "F.SilkS")
		)
		(fp_line
			(start -1.651 -1.905)
			(end 1.651 -1.905)
			(stroke
				(width 0.1524)
				(type default)
			)
			(layer "F.SilkS")
		)
		(fp_poly
			(pts
				(xy -1.524 0.7112) (xy -1.524 1.7526) (xy -0.508 1.7526) (xy -0.508 0.6985) (xy 0.508 0.6985) (xy 0.508 1.7526)
				(xy 1.524 1.7526) (xy 1.524 0.6985) (xy 1.524 -0.6985) (xy 0.508 -0.6985) (xy 0.508 -1.7526) (xy -0.508 -1.7526)
				(xy -0.508 -0.6985) (xy -1.524 -0.6985) (xy -1.524 0.6985)
			)
			(stroke
				(width 0)
				(type default)
			)
			(fill no)
			(layer "F.CrtYd")
		)
		(fp_text user "2"
			(at 2.046224 1.611122 0)
			(unlocked yes)
			(layer "F.SilkS")
			(effects
				(font
					(size 0.635 0.4064)
					(thickness 0.1524)
				)
			)
		)
		(fp_text user "3"
			(at 1.048004 -0.118618 0)
			(unlocked yes)
			(layer "F.SilkS")
			(effects
				(font
					(size 0.635 0.4064)
					(thickness 0.1524)
				)
			)
		)
		(fp_text user "1"
			(at -2.342896 2.741422 0)
			(unlocked yes)
			(layer "F.SilkS")
			(effects
				(font
					(size 0.635 0.4064)
					(thickness 0.1524)
				)
			)
		)
		(pad "1" smd rect
			(at -1.016 1.1176 180)
			(size 1.016 1.27)
			(layers "F.Cu" "F.Mask" "F.Paste")
			(net "GND")
		)
		(pad "2" smd rect
			(at 1.016 1.1176 180)
			(size 1.016 1.27)
			(layers "F.Cu" "F.Mask" "F.Paste")
			(net "P5V_CRT")
		)
		(pad "3" smd rect
			(at 0 -1.1176 180)
			(size 1.016 1.27)
			(layers "F.Cu" "F.Mask" "F.Paste")
			(net "CRT_DDCCLK")
		)
	)
	(footprint ""
		(layer "F.Cu")
		(at 68.61429 -177.760376 90)
		(property "Reference" "D25"
			(at 2.054606 0.570484 90)
			(unlocked yes)
			(layer "F.SilkS")
			(effects
				(font
					(size 0.7874 0.5842)
					(thickness 0.1524)
				)
				(justify left)
			)
		)
		(property "Value" ""
			(at 0 0 90)
			(layer "F.Fab")
			(effects
				(font
					(size 1.27 1.27)
				)
			)
		)
		(duplicate_pad_numbers_are_jumpers no)
		(fp_line
			(start 1.778 -0.5588)
			(end 1.3208 -0.5588)
			(stroke
				(width 0.1524)
				(type default)
			)
			(layer "F.SilkS")
		)
		(fp_line
			(start 1.778 -0.5588)
			(end 1.778 0.5588)
			(stroke
				(width 0.1524)
				(type default)
			)
			(layer "F.SilkS")
		)
		(fp_line
			(start 1.4732 -0.5588)
			(end 1.4732 0.5588)
			(stroke
				(width 0.1524)
				(type default)
			)
			(layer "F.SilkS")
		)
		(fp_line
			(start 1.3208 -0.5588)
			(end 1.3208 0.5588)
			(stroke
				(width 0.1524)
				(type default)
			)
			(layer "F.SilkS")
		)
		(fp_line
			(start -1.3208 -0.5588)
			(end 1.3208 -0.5588)
			(stroke
				(width 0.1524)
				(type default)
			)
			(layer "F.SilkS")
		)
		(fp_line
			(start 1.778 0.5588)
			(end 1.3208 0.5588)
			(stroke
				(width 0.1524)
				(type default)
			)
			(layer "F.SilkS")
		)
		(fp_line
			(start 1.6256 0.5588)
			(end 1.6256 -0.5588)
			(stroke
				(width 0.1524)
				(type default)
			)
			(layer "F.SilkS")
		)
		(fp_line
			(start 1.3208 0.5588)
			(end -1.3208 0.5588)
			(stroke
				(width 0.1524)
				(type default)
			)
			(layer "F.SilkS")
		)
		(fp_line
			(start -1.3208 0.5588)
			(end -1.3208 -0.5588)
			(stroke
				(width 0.1524)
				(type default)
			)
			(layer "F.SilkS")
		)
		(fp_rect
			(start -1.1684 0.508)
			(end 1.1684 -0.508)
			(stroke
				(width 0)
				(type default)
			)
			(fill no)
			(layer "F.CrtYd")
		)
		(fp_line
			(start 0.899922 -0.40005)
			(end 0.899922 0.40005)
			(stroke
				(width 0.1)
				(type default)
			)
			(layer "F.Fab")
		)
		(fp_line
			(start -0.899922 -0.40005)
			(end 0.899922 -0.40005)
			(stroke
				(width 0.1)
				(type default)
			)
			(layer "F.Fab")
		)
		(fp_line
			(start 0.899922 0.40005)
			(end -0.899922 0.40005)
			(stroke
				(width 0.1)
				(type default)
			)
			(layer "F.Fab")
		)
		(fp_line
			(start -0.899922 0.40005)
			(end -0.899922 -0.40005)
			(stroke
				(width 0.1)
				(type default)
			)
			(layer "F.Fab")
		)
		(fp_text user "-"
			(at 1.105154 0.763524 90)
			(unlocked yes)
			(layer "F.SilkS")
			(effects
				(font
					(size 1.27 0.9652)
					(thickness 0.1524)
				)
				(justify left)
			)
		)
		(pad "A" smd rect
			(at -0.750062 0 90)
			(size 0.8128 0.8128)
			(layers "F.Cu" "F.Mask" "F.Paste")
			(net "WDT_LED")
		)
		(pad "C" smd rect
			(at 0.750062 0 90)
			(size 0.8128 0.8128)
			(layers "F.Cu" "F.Mask" "F.Paste")
			(net "GND")
		)
	)
)
